FILE_TYPE = MULTI_PHYS_TABLE;
PART 'CONN8_H62179001'
{=====================================================================================================================================================================================================================================}
:PACK_TYPE | MATERIAL | PART_NUMBER     = EnvComp | PART_NUMBER  | JEDEC_TYPE             | DESCRIPTION                              | CLASS | COMPONENT_TYPE | HEIGHT     | LEAD_LENGTH  | SPEED_URL | Status |RPL| AML | Bus_Unit | Days;
{=====================================================================================================================================================================================================================================}
'TH'       | 'CONN'   | 'H62179-001'(!) = ''      | 'H62179-001' | 'CONN8_H62179001'      | 'CONN,HDR,1X8,PLG,VT,1.25MM,093ST,KPSHR' | 'IO'  | 'THMT'         | '0.193 IN' | '0.091'      | 'http://speed.intel.com:8081/speed/module/pdm/item/pdm_item_detail_direct.asp?item_cde=H62179-001&item_rev=01&url_param=unused' | '' | '' | '' | '' | '' 
'TH'       | 'EMPTY'  | 'H62179-001'(!) = ''      | 'H62179-001' | 'CONN8_H62179001'      | 'CONN,HDR,1X8,PLG,VT,1.25MM,093ST,KPSHR' | 'IO'  | 'THMT'         | '0.193 IN' | '0.091'      | 'http://speed.intel.com:8081/speed/module/pdm/item/pdm_item_detail_direct.asp?item_cde=H62179-001&item_rev=01&url_param=unused' | '' | '' | '' | '' | '' 
'PIP'      | 'CONN'   | 'H62179-001'(!) = ''      | 'H62179-001' | 'CONN8_H62179001_PIP'  | 'CONN,HDR,1X8,PLG,VT,1.25MM,093ST,KPSHR' | 'IO'  | 'THMT'         | '0.193 IN' | '0.091'      | 'http://speed.intel.com:8081/speed/module/pdm/item/pdm_item_detail_direct.asp?item_cde=H62179-001&item_rev=01&url_param=unused' | '' | '' | '' | '' | '' 
'PIP'      | 'EMPTY'  | 'H62179-001'(!) = ''      | 'H62179-001' | 'CONN8_H62179001_PIP'  | 'CONN,HDR,1X8,PLG,VT,1.25MM,093ST,KPSHR' | 'IO'  | 'THMT'         | '0.193 IN' | '0.091'      | 'http://speed.intel.com:8081/speed/module/pdm/item/pdm_item_detail_direct.asp?item_cde=H62179-001&item_rev=01&url_param=unused' | '' | '' | '' | '' | '' 
END_PART
END.
